FILE_TYPE = CONNECTIVITY;
{Allegro Design Entry HDL 16.6-p007 (v16-6-112F) 10/10/2012}
"PAGE_NUMBER" = 219;
0"NC";
1"PVDDQ_DEF\g";
2"GND\g";
3"GND\g";
4"P5V_STBY\g";
5"GND\g";
6"GND\g";
7"GND\g";
8"GND\g";
9"GND\g";
10"GND\g";
11"GND\g";
12"PVDDQ_DEF\g";
13"GND\g";
14"GND\g";
15"GND\g";
16"VR_FET_SW_P12V_STBY_PVDDQ_DEF\g";
17"GND\g";
18"VR_FET_SW_P12V_STBY_PVDDQ_DEF\g";
19"P5V_STBY\g";
20"VR_PVDDQ_DEF_PH2_BOOT";
21"VR_PVDDQ_DEF_PH2_VCIN";
22"VR_PVDDQ_DEF_PWM2";
23"VR_PVDDQ_DEF_PH1_OCSET"VOLTAGE"3.6";
24"VR_PVDDQ_DEF_PH1_VCIN";
25"VR_PVDDQ_DEF_PH2_BOOT_R";
26"VR_PVDDQ_DEF_AIREF2";
27"A_TSENSE_PVDDQ_DEF";
28"VR_PVDDQ_DEF_PH2_SW";
29"VR_PVDDQ_DEF_PH2_OCSET"VOLTAGE"3.6";
30"VR_PVDDQ_DEF_PH1_PHASE";
31"VR_PVDDQ_DEF_PH1_BOOT";
32"TP_PVDDQ_DEF_PH2_GL_1";
33"TP_PVDDQ_DEF_PH2_GL_0";
34"VR_PVDDQ_DEF_PH2_PHASE";
35"VR_PVDDQ_DEF_PH2_SW_RC";
36"VR_PVDDQ_DEF_PWM1";
37"TP_PVDDQ_DEF_PH1_GL_0";
38"VR_PVDDQ_DEF_AIREF1";
39"ISENSE_PVDDQ_DEF_PH2_IMON";
40"VR_PVDDQ_DEF_PH1_SW_RC";
41"VR_PVDDQ_DEF_PH1_BOOT_R";
42"VR_PVDDQ_DEF_PH1_SW";
43"A_TSENSE_PVDDQ_DEF";
44"ISENSE_PVDDQ_DEF_PH1_IMON";
45"TP_PVDDQ_DEF_PH1_GL_1";
46"GND\g";
%"PVDDQ_DEF"
"1","(4450,1925)","0","mstr_symbols","I1";
;
HDL_POWER"PVDDQ_DEF"
BODY_TYPE"PLUMBING"
CDS_LIB"mstr_symbols"
VOLTAGE"1.2V";
"G\NAC"1;
%"IR354XX"
"1","(1750,2125)","0","mstr_discrete","I106";
;
CDS_SEC"1"
NO_XNET_CONNECTION"1"
MATERIAL"IC"
PART_NUMBER"H73688-001"
LOCATION"EU7A1"
VALUE"IR35411"
CDS_LOCATION"EU7A1"
SEC"1"
SEC_TYPE"SM"
PACK_TYPE"SM"
CDS_LIB"mstr_discrete";
"TOUT_FLT"
$PN"36"43;
"NC"
$PN"31"0;
"OCSET"
$PN"37"23;
"IOUT"
$PN"38"44;
"SW"
$PN"10"42;
"BOOST"
$PN"33"41;
"REFIN"
$PN"39"38;
"PWM"
$PN"34"36;
"PHASE"
$PN"32"30;
"VIN<0>"
$PN"25"18;
"VCC"
$PN"3"24;
"VIN<1>"
$PN"30"18;
"EN"
$PN"35"4;
"VDRV"
$PN"4"4;
"VOS"
$PN"1"1;
"LGND"
$PN"2"10;
"PGND<1>"
$PN"7"10;
"PGND<2>"
$PN"40"10;
"PGND<0>"
$PN"5"10;
"GL<0>"
$PN"6"37;
"GL<1>"
$PN"41"45;
%"IR354XX"
"1","(1775,-125)","0","mstr_discrete","I107";
;
CDS_SEC"1"
BOM_SS"NOPOP"
PART_NUMBER"H73688-001"
NO_XNET_CONNECTION"1"
MATERIAL"IC"
LOCATION"EU7A4"
PACK_TYPE"SM"
SEC_TYPE"SM"
SEC"1"
CDS_LOCATION"EU7A4"
CDS_LIB"mstr_discrete"
VALUE"IR35411";
"TOUT_FLT"
$PN"36"27;
"NC"
$PN"31"0;
"OCSET"
$PN"37"29;
"IOUT"
$PN"38"39;
"SW"
$PN"10"28;
"BOOST"
$PN"33"25;
"REFIN"
$PN"39"26;
"PWM"
$PN"34"22;
"PHASE"
$PN"32"34;
"VIN<0>"
$PN"25"16;
"VCC"
$PN"3"21;
"VIN<1>"
$PN"30"16;
"EN"
$PN"35"19;
"VDRV"
$PN"4"19;
"VOS"
$PN"1"12;
"LGND"
$PN"2"15;
"PGND<1>"
$PN"7"15;
"PGND<2>"
$PN"40"15;
"PGND<0>"
$PN"5"15;
"GL<0>"
$PN"6"33;
"GL<1>"
$PN"41"32;
%"RES"
"2","(4575,2300)","0","mstr_discrete","I108";
;
CDS_LOCATION"R7A20"
WATTAGE"1/16W"
MATERIAL"EMPTY"
VALUE"68.1K"
LOCATION"R7A20"
PACK_TYPE"0402"
PART_NUMBER"G21796-187"
TOLERANCE"1%"
CDS_LIB"mstr_discrete"
$SEC"1"
CDS_SEC"1";
"A"
$PN"1"23;
"B"
$PN"2"2;
%"GND"
"1","(4575,2125)","0","mstr_symbols","I109";
;
VOLTAGE"0"
SIZE"1B"
CDS_LIB"mstr_symbols"
BOM_COST"PROC_VRD_VCCIN_CPU0"
ROOM"PVCCIN_CPU0_PWR_VR"
BODY_TYPE"PLUMBING"
HDL_POWER"GND";
"A\NAC"2;
%"RES"
"2","(4575,25)","0","mstr_discrete","I110";
;
CDS_SEC"1"
CDS_LOCATION"R7A21"
BOM_SS"NOPOP"
LOCATION"R7A21"
VALUE"68.1K"
WATTAGE"1/16W"
MATERIAL"EMPTY"
PACK_TYPE"0402"
TOLERANCE"1%"
PART_NUMBER"G21796-187"
SEC_TYPE"0402"
SEC"1"
CDS_LIB"mstr_discrete";
"A"
$PN"1"29;
"B"
$PN"2"3;
%"GND"
"1","(4575,-175)","0","mstr_symbols","I111";
;
VOLTAGE"0"
SIZE"1B"
CDS_LIB"mstr_symbols"
BOM_COST"PROC_VRD_VCCIN_CPU0"
ROOM"PVCCIN_CPU0_PWR_VR"
BODY_TYPE"PLUMBING"
HDL_POWER"GND";
"A\NAC"3;
%"P5V_STBY"
"1","(225,3150)","0","mstr_symbols","I112";
;
HDL_POWER"P5V_STBY"
BODY_TYPE"PLUMBING"
VOLTAGE"5.0V"
CDS_LIB"mstr_symbols"
SIZE"1B";
"G\NAC"4;
%"CAP_A"
"1","(1075,-625)","0","dev_discrete","I113";
;
CDS_SEC"1"
CDS_LOCATION"CT46"
VOLTAGE"16V"
TOLERANCE"10%"
MATERIAL"X7R"
PACK_TYPE"0402V"
POP"NOPOP"
BOM_SS"NOPOP"
VALUE"0.1UF"
PART_NUMBER"A36096-030"
LOCATION"CT46"
SEC_TYPE"0402V"
SEC"1"
CDS_LIB"dev_discrete"
ROOM"PVCCIN_CPU0_PWR_VR";
"B"
$PN"2"5;
"A"
$PN"1"26;
%"GND"
"1","(1075,-900)","0","mstr_symbols","I114";
;
CDS_LIB"mstr_symbols"
ROOM"PVCCIN_CPU0_PWR_VR"
BOM_COST"PROC_VRD_VCCIN_CPU0"
SIZE"1B"
VOLTAGE"0"
BODY_TYPE"PLUMBING"
HDL_POWER"GND";
"A\NAC"5;
%"CAP_A"
"1","(1025,1625)","0","dev_discrete","I116";
;
CDS_SEC"1"
CDS_LOCATION"CT45"
PACK_TYPE"0402V"
TOLERANCE"10%"
MATERIAL"X7R"
VALUE"0.1UF"
VOLTAGE"16V"
LOCATION"CT45"
PART_NUMBER"A36096-030"
POP"NOPOP"
ROOM"PVCCIN_CPU0_PWR_VR"
CDS_LIB"dev_discrete"
SEC"1"
SEC_TYPE"0402V";
"B"
$PN"2"6;
"A"
$PN"1"38;
%"GND"
"1","(1025,1375)","0","mstr_symbols","I117";
;
HDL_POWER"GND"
BODY_TYPE"PLUMBING"
CDS_LIB"mstr_symbols"
ROOM"PVCCIN_CPU0_PWR_VR"
BOM_COST"PROC_VRD_VCCIN_CPU0"
SIZE"1B"
VOLTAGE"0";
"A\NAC"6;
%"CAP"
"1","(3075,-100)","0","mstr_discrete","I119";
;
CDS_SEC"1"
CDS_LOCATION"CT48"
VALUE"1000PF"
VOLTAGE"50V"
POP"NOPOP"
TOLERANCE"10%"
MATERIAL"X7R"
PART_NUMBER"A36096-046"
PACK_TYPE"0402LF"
BOM_SS"NOPOP"
LOCATION"CT48"
SEC_TYPE"0402LF"
SEC"1"
CDS_LIB"mstr_discrete"
ROOM"VDDQ_KLM_PWR_VR";
"A"
$PN"1"27;
"B"
$PN"2"7;
%"GND"
"1","(3075,-300)","0","mstr_symbols","I120";
;
CDS_LIB"mstr_symbols"
SIZE"1B"
VOLTAGE"0"
ROOM"VDDQ_KLM_PWR_VR"
BODY_TYPE"PLUMBING"
HDL_POWER"GND";
"A\NAC"7;
%"GND"
"1","(2875,-1125)","0","mstr_symbols","I122";
;
CDS_LIB"mstr_symbols"
ROOM"PVCCIN_CPU0_PWR_VR"
BOM_COST"PROC_VRD_VCCIN_CPU0"
VOLTAGE"0"
SIZE"1B"
BODY_TYPE"PLUMBING"
HDL_POWER"GND";
"A\NAC"8;
%"CAP"
"1","(2900,2125)","0","mstr_discrete","I124";
;
CDS_SEC"1"
CDS_LOCATION"CT43"
PART_NUMBER"A36096-046"
MATERIAL"X7R"
TOLERANCE"10%"
VOLTAGE"50V"
LOCATION"CT43"
VALUE"1000PF"
PACK_TYPE"0402LF"
POP"NOPOP"
ROOM"VDDQ_KLM_PWR_VR"
CDS_LIB"mstr_discrete"
SEC"1"
SEC_TYPE"0402LF";
"A"
$PN"1"43;
"B"
$PN"2"9;
%"GND"
"1","(2900,1925)","0","mstr_symbols","I125";
;
HDL_POWER"GND"
BODY_TYPE"PLUMBING"
SIZE"1B"
VOLTAGE"0"
ROOM"VDDQ_KLM_PWR_VR"
CDS_LIB"mstr_symbols";
"A\NAC"9;
%"GND"
"1","(2850,1150)","0","mstr_symbols","I128";
;
CDS_LIB"mstr_symbols"
ROOM"PVCCIN_CPU0_PWR_VR"
BOM_COST"PROC_VRD_VCCIN_CPU0"
VOLTAGE"0"
SIZE"1B"
BODY_TYPE"PLUMBING"
HDL_POWER"GND";
"A\NAC"46;
%"CAP"
"1","(2850,1625)","0","mstr_discrete","I137";
;
CDS_SEC"1"
CDS_LOCATION"CT44"
LOCATION"CT44"
TOLERANCE"10%"
MATERIAL"X7R"
VOLTAGE"50V"
VALUE"1000PF"
PACK_TYPE"0402LF"
PART_NUMBER"A36096-046"
POP"NOPOP"
SEC_TYPE"0402LF"
SEC"1"
CDS_LIB"mstr_discrete"
ROOM"VDDQ_KLM_PWR_VR";
"A"
$PN"1"42;
"B"
$PN"2"40;
%"CAP"
"1","(2875,-600)","0","mstr_discrete","I138";
;
CDS_SEC"1"
CDS_LOCATION"CT47"
PART_NUMBER"A36096-046"
POP"NOPOP"
VOLTAGE"50V"
VALUE"1000PF"
MATERIAL"X7R"
LOCATION"CT47"
BOM_SS"NOPOP"
PACK_TYPE"0402LF"
TOLERANCE"10%"
CDS_LIB"mstr_discrete"
ROOM"VDDQ_KLM_PWR_VR"
SEC"1"
SEC_TYPE"0402LF";
"A"
$PN"1"28;
"B"
$PN"2"35;
%"RES"
"1","(-125,1900)","0","mstr_discrete","I141";
;
CDS_SEC"1"
CDS_LOCATION"RT30"
WATTAGE"1/10W"
VALUE"0"
TOLERANCE"5.0%"
PACK_TYPE"0603"
LOCATION"RT30"
MATERIAL"CHIP"
PART_NUMBER"G22178-002"
ROOM"NIC_SPRV"
BOM_COST"NT_GBE_BASE"
CDS_LIB"mstr_discrete"
SEC"1"
SEC_TYPE"0603";
"B"
$PN"2"41;
"A"
$PN"1"31;
%"RES"
"1","(175,-350)","0","mstr_discrete","I142";
;
CDS_SEC"1"
CDS_LOCATION"RT31"
BOM_SS"NOPOP"
PART_NUMBER"G22178-002"
TOLERANCE"5.0%"
LOCATION"RT31"
WATTAGE"1/10W"
VALUE"0"
PACK_TYPE"0603"
MATERIAL"CHIP"
SEC"1"
SEC_TYPE"0603"
CDS_LIB"mstr_discrete"
BOM_COST"NT_GBE_BASE"
ROOM"NIC_SPRV";
"B"
$PN"2"25;
"A"
$PN"1"20;
%"RES"
"1","(-725,3000)","0","mstr_discrete","I147";
;
LOCATION"R3L6"
PACK_TYPE"0402"
TOLERANCE"5%"
MATERIAL"CHIP"
WATTAGE"1/16W"
PART_NUMBER"G21497-005"
VALUE"0.0"
CDS_LOCATION"R3L6"
CDS_SEC"1"
ROOM"CPU0"
SEC"1"
SEC_TYPE"0402"
CDS_LIB"mstr_discrete"
BOM_COST"PROC_SIDEBAND";
"B"
$PN"2"4;
"A"
$PN"1"24;
%"RES"
"1","(-775,700)","0","mstr_discrete","I148";
;
WATTAGE"1/16W"
BOM_SS"NOPOP"
LOCATION"R3L8"
VALUE"0.0"
TOLERANCE"5%"
PART_NUMBER"G21497-005"
PACK_TYPE"0402"
MATERIAL"CHIP"
CDS_LOCATION"R3L8"
BOM_COST"PROC_SIDEBAND"
CDS_LIB"mstr_discrete"
SEC_TYPE"0402"
SEC"1"
ROOM"CPU0"
CDS_SEC"1";
"B"
$PN"2"19;
"A"
$PN"1"21;
%"SC1U10V2KX-4-GP"
"1","(-450,2350)","0","w_hdl","I151";
;
CDS_SEC"1"
CDS_LOCATION"C7A18"
VALUE"SC1U10V2KX-4-GP"
LOCATION"C7A18"
TOLERANCE"10%"
RATED"10V"
PACK_SIZE"0402"
ATTRIBUTE"1UF"
PART_NUMBER"78.10523.8FL"
CDS_LIB"w_hdl"
CDS_LMAN_SYM_OUTLINE"-50,25,50,-25"
SEC_TYPE"SMD-BCG6"
SEC"1"
PACK_TYPE"SMD-BCG6";
"2"
$PN"2"11;
"1"
$PN"1"4;
%"SC1U10V2KX-4-GP"
"1","(-525,100)","0","w_hdl","I152";
;
CDS_SEC"1"
CDS_LOCATION"C7A26"
BOM_SS"NOPOP"
ATTRIBUTE"1UF"
TOLERANCE"10%"
RATED"10V"
PACK_SIZE"0402"
LOCATION"C7A26"
VALUE"SC1U10V2KX-4-GP"
PART_NUMBER"78.10523.8FL"
CDS_LIB"w_hdl"
CDS_LMAN_SYM_OUTLINE"-50,25,50,-25"
PACK_TYPE"SMD-BCG6"
SEC"1"
SEC_TYPE"SMD-BCG6";
"2"
$PN"2"17;
"1"
$PN"1"19;
%"1R3F-GP"
"1","(2850,1325)","0","w_hdl","I153";
;
CDS_SEC"1"
CDS_LOCATION"RT29"
TOLERANCE"1%"
ATTRIBUTE"1 OHM"
RATED"1/10W"
PACK_SIZE"0603"
VALUE"1R3F-GP"
LOCATION"RT29"
POP"NOPOP"
PACK_TYPE"RCL_GP"
SEC"1"
SEC_TYPE"RCL_GP"
PART_NUMBER"64.1R005.55L"
CDS_LIB"w_hdl"
CDS_LMAN_SYM_OUTLINE"-50,75,50,-75";
"2"
$PN"2"46;
"1"
$PN"1"40;
%"1R3F-GP"
"1","(2875,-925)","0","w_hdl","I154";
;
CDS_SEC"1"
CDS_LOCATION"RT32"
POP"NOPOP"
BOM_SS"NOPOP"
ATTRIBUTE"1 OHM"
VALUE"1R3F-GP"
TOLERANCE"1%"
LOCATION"RT32"
RATED"1/10W"
PACK_SIZE"0603"
PACK_TYPE"RCL_GP"
SEC"1"
SEC_TYPE"RCL_GP"
PART_NUMBER"64.1R005.55L"
CDS_LIB"w_hdl"
CDS_LMAN_SYM_OUTLINE"-50,75,50,-75";
"2"
$PN"2"8;
"1"
$PN"1"35;
%"IND-120NH-30-GP"
"1","(3850,1850)","1","w_hdl","I157";
;
CDS_SEC"1"
CDS_LOCATION"L7A1"
DS_VALUE"90NH"
SS_ISAT"94A@25C"
LOCATION"L7A1"
NEW_PACK_SIZE"DCR=0.17MOHM"
BOM_SS"068.1202N.M001"
SS_VALUE"120NH"
BOM_DS"068.9002N.1021"
NEW_TYPE"IRMS=66A@DELTA_T<40C"
NEW_RATED"DS_ISAT=134A@25C"
TYPE"IRMS=66A@DELTA_T<40C"
PACK_SIZE"DCR=0.17MOHM"
RATED"ISAT=94A@25C"
ATTRIBUTE"120NH"
VALUE"IND-120NH-30-GP"
PACK_TYPE"DISCRET-GB2"
SEC"1"
SEC_TYPE"DISCRET-GB2"
CDS_LMAN_SYM_OUTLINE"-75,100,75,-100"
CDS_LIB"w_hdl"
PART_NUMBER"068.1202N.M001";
"F"
$PN"2"1;
"S"
$PN"1"42;
%"IND-120NH-30-GP"
"1","(3850,-400)","1","w_hdl","I158";
;
CDS_SEC"1"
CDS_LOCATION"L7A3"
BOM_SS"NOPOP"
LOCATION"L7A3"
DS_VALUE"90NH"
NEW_PACK_SIZE"DCR=0.17MOHM"
NEW_RATED"DS_ISAT=134A@25C"
BOM_DS"068.9002N.1021"
NEW_TYPE"IRMS=66A@DELTA_T<40C"
PART_NUMBER"068.1202N.M001"
CDS_LIB"w_hdl"
CDS_LMAN_SYM_OUTLINE"-75,100,75,-100"
SEC_TYPE"DISCRET-GB2"
SEC"1"
PACK_TYPE"DISCRET-GB2"
VALUE"IND-120NH-30-GP"
ATTRIBUTE"120NH"
RATED"ISAT=94A@25C"
PACK_SIZE"DCR=0.17MOHM"
TYPE"IRMS=66A@DELTA_T<40C";
"F"
$PN"2"12;
"S"
$PN"1"28;
%"GND"
"1","(2300,1500)","0","mstr_symbols","I19";
;
HDL_POWER"GND"
BODY_TYPE"PLUMBING"
ROOM"VDDQ_DEF_PWR_VR"
BOM_COST"PROC_VRD_VCCIN_CPU0"
SIZE"1B"
CDS_LIB"mstr_symbols"
VOLTAGE"0";
"A\NAC"10;
%"GND"
"1","(-2225,2000)","0","mstr_symbols","I35";
;
HDL_POWER"GND"
BODY_TYPE"PLUMBING"
BOM_COST"PROC_VRD_VCCIN_CPU0"
ROOM"VDDQ_DEF_PWR_VR"
VOLTAGE"0"
CDS_LIB"mstr_symbols"
SIZE"1B";
"A\NAC"11;
%"CAP"
"1","(-1100,1775)","2","mstr_discrete","I44";
;
CDS_SEC"1"
LOCATION"C7A12"
PART_NUMBER"A36096-104"
VOLTAGE"16V"
PACK_TYPE"0402"
TOLERANCE"10%"
MATERIAL"X7R"
VALUE"0.220UF"
CDS_LIB"mstr_discrete"
SPOF"TRUE"
CDS_LOCATION"C7A12"
ROOM"VDDQ_DEF_PWR_VR"
SEC"1"
SEC_TYPE"0402";
"A"
$PN"1"31;
"B"
$PN"2"30;
%"CAP"
"1","(-2225,2425)","0","mstr_discrete","I45";
;
CDS_SEC"1"
VALUE"10UF"
LOCATION"C3L2"
MATERIAL"X6S"
TOLERANCE"10%"
VOLTAGE"16V"
PART_NUMBER"C95333-007"
PACK_TYPE"0805"
ROOM"VDDQ_DEF_PWR_VR"
CDS_LOCATION"C3L2"
CDS_LIB"mstr_discrete"
SEC"1"
SEC_TYPE"0805";
"A"
$PN"1"18;
"B"
$PN"2"11;
%"CAP"
"1","(-2000,2425)","0","mstr_discrete","I46";
;
CDS_SEC"1"
VOLTAGE"16V"
TOLERANCE"10%"
MATERIAL"X6S"
PART_NUMBER"C95333-007"
VALUE"10UF"
PACK_TYPE"0805"
LOCATION"C3L4"
CDS_LIB"mstr_discrete"
CDS_LOCATION"C3L4"
ROOM"VDDQ_DEF_PWR_VR"
SEC"1"
SEC_TYPE"0805";
"A"
$PN"1"18;
"B"
$PN"2"11;
%"CAP"
"1","(-1775,2425)","0","mstr_discrete","I47";
;
CDS_SEC"1"
VALUE"10UF"
PART_NUMBER"C95333-007"
MATERIAL"X6S"
TOLERANCE"10%"
PACK_TYPE"0805"
VOLTAGE"16V"
LOCATION"C3L13"
ROOM"VDDQ_DEF_PWR_VR"
CDS_LOCATION"C3L13"
CDS_LIB"mstr_discrete"
SEC"1"
SEC_TYPE"0805";
"A"
$PN"1"18;
"B"
$PN"2"11;
%"CAP"
"1","(-1475,2425)","0","mstr_discrete","I48";
;
CDS_SEC"1"
VALUE"1.0UF"
PACK_TYPE"0402"
TOLERANCE"10%"
VOLTAGE"16V"
LOCATION"C7A11"
MATERIAL"X6S"
PART_NUMBER"D97712-011"
ROOM"VDDQ_DEF_PWR_VR"
CDS_LOCATION"C7A11"
CDS_LIB"mstr_discrete"
SEC"1"
SEC_TYPE"0402";
"A"
$PN"1"18;
"B"
$PN"2"11;
%"CAP"
"1","(-875,2425)","0","mstr_discrete","I50";
;
CDS_SEC"1"
PACK_TYPE"0402"
MATERIAL"X6S"
TOLERANCE"10%"
LOCATION"C7A16"
VALUE"1.0UF"
PART_NUMBER"D97712-011"
VOLTAGE"16V"
ROOM"VDDQ_DEF_PWR_VR"
CDS_LOCATION"C7A16"
CDS_LIB"mstr_discrete"
SEC"1"
SEC_TYPE"0402";
"A"
$PN"1"24;
"B"
$PN"2"11;
%"CAP_A"
"1","(-1175,2425)","0","dev_discrete","I51";
;
CDS_SEC"1"
LOCATION"C7A5"
PART_NUMBER"A36096-030"
MATERIAL"X7R"
TOLERANCE"10%"
VOLTAGE"16V"
VALUE"0.1UF"
PACK_TYPE"0402V"
CDS_LIB"dev_discrete"
CDS_LOCATION"C7A5"
ROOM"VDDQ_DEF_PWR_VR"
SEC"1"
SEC_TYPE"0402V";
"B"
$PN"2"11;
"A"
$PN"1"18;
%"CAP"
"1","(-125,2425)","0","mstr_discrete","I54";
;
CDS_SEC"1"
VALUE"0.22UF"
LOCATION"C7A17"
VOLTAGE"16V"
TOLERANCE"10%"
PART_NUMBER"A36096-155"
PACK_TYPE"0402"
MATERIAL"X7R"
CDS_LOCATION"C7A17"
CDS_LIB"mstr_discrete"
ROOM"VDDQ_DEF_PWR_VR"
SEC"1"
SEC_TYPE"0402";
"A"
$PN"1"4;
"B"
$PN"2"11;
%"PVDDQ_DEF"
"1","(4500,-325)","0","mstr_symbols","I64";
;
HDL_POWER"PVDDQ_DEF"
BODY_TYPE"PLUMBING"
VOLTAGE"1.2V"
ROOM"VDDQ_DEF_PWR_VR"
CDS_LIB"mstr_symbols"
BOM_COST"PROC_SOCKET ";
"G\NAC"12;
%"CAP"
"1","(4500,-575)","0","mstr_discrete","I68";
;
CDS_SEC"1"
VOLTAGE"4V"
LOCATION"C6A4"
GROUP"PWR_MLCC_CAP"
MATERIAL"X6S"
PART_NUMBER"C95333-002"
PACK_TYPE"0805LF"
VALUE"22UF"
BOM_SS"NOPOP"
TOLERANCE"20%"
CDS_LIB"mstr_discrete"
CDS_LOCATION"C6A4"
ROOM"VDDQ_DEF_PWR_VR"
BOM_COST"PROC_VRD_VCCIN_CPU0"
SEC"1"
SEC_TYPE"0805LF";
"A"
$PN"1"12;
"B"
$PN"2"13;
%"GND"
"1","(4500,-750)","0","mstr_symbols","I69";
;
HDL_POWER"GND"
BODY_TYPE"PLUMBING"
ROOM"VDDQ_DEF_PWR_VR"
BOM_COST"PROC_VRD_VCCIN_CPU0"
SIZE"1B"
CDS_LIB"mstr_symbols"
VOLTAGE"0";
"A\NAC"13;
%"GND"
"1","(4450,1500)","0","mstr_symbols","I7";
;
SIZE"1B"
CDS_LIB"mstr_symbols"
VOLTAGE"0"
BOM_COST"PROC_VRD_VCCIN_CPU0"
ROOM"VDDQ_DEF_PWR_VR"
BODY_TYPE"PLUMBING"
HDL_POWER"GND";
"A\NAC"14;
%"GND"
"1","(2325,-750)","0","mstr_symbols","I70";
;
HDL_POWER"GND"
BODY_TYPE"PLUMBING"
ROOM"VDDQ_DEF_PWR_VR"
BOM_COST"PROC_VRD_VCCIN_CPU0"
SIZE"1B"
VOLTAGE"0"
CDS_LIB"mstr_symbols";
"A\NAC"15;
%"CAP"
"1","(-100,175)","0","mstr_discrete","I72";
;
CDS_SEC"1"
PACK_TYPE"0402"
BOM_SS"NOPOP"
TOLERANCE"10%"
VOLTAGE"16V"
VALUE"0.22UF"
LOCATION"C7A25"
PART_NUMBER"A36096-155"
MATERIAL"X7R"
CDS_LIB"mstr_discrete"
ROOM"VDDQ_DEF_PWR_VR"
CDS_LOCATION"C7A25"
SEC"1"
SEC_TYPE"0402";
"A"
$PN"1"19;
"B"
$PN"2"17;
%"CAP"
"1","(-800,-525)","2","mstr_discrete","I75";
;
CDS_SEC"1"
PART_NUMBER"A36096-104"
MATERIAL"X7R"
PACK_TYPE"0402"
VOLTAGE"16V"
TOLERANCE"10%"
LOCATION"C7A22"
VALUE"0.220UF"
BOM_SS"NOPOP"
SEC_TYPE"0402"
SEC"1"
CDS_LIB"mstr_discrete"
SPOF"TRUE"
CDS_LOCATION"C7A22"
ROOM"VDDQ_DEF_PWR_VR";
"A"
$PN"1"20;
"B"
$PN"2"34;
%"CAP"
"1","(-925,75)","0","mstr_discrete","I77";
;
CDS_SEC"1"
VALUE"1.0UF"
VOLTAGE"16V"
TOLERANCE"10%"
MATERIAL"X6S"
PACK_TYPE"0402"
LOCATION"C7A24"
PART_NUMBER"D97712-011"
BOM_SS"NOPOP"
SEC_TYPE"0402"
SEC"1"
ROOM"VDDQ_DEF_PWR_VR"
CDS_LOCATION"C7A24"
CDS_LIB"mstr_discrete";
"A"
$PN"1"21;
"B"
$PN"2"17;
%"CAP_A"
"1","(-1250,75)","0","dev_discrete","I78";
;
VALUE"0.1UF"
VOLTAGE"16V"
PACK_TYPE"0402V"
MATERIAL"X7R"
TOLERANCE"10%"
LOCATION"C7A20"
PART_NUMBER"A36096-030"
CDS_LOCATION"C7A20"
CDS_LIB"dev_discrete"
ROOM"VDDQ_DEF_PWR_VR"
CDS_SEC"1"
SEC_TYPE"0402V"
SEC"1";
"B"
$PN"2"17;
"A"
$PN"1"16;
%"CAP"
"1","(-1525,75)","0","mstr_discrete","I79";
;
CDS_SEC"1"
VALUE"1.0UF"
MATERIAL"X6S"
PACK_TYPE"0402"
TOLERANCE"10%"
VOLTAGE"16V"
PART_NUMBER"D97712-011"
LOCATION"C7A21"
CDS_LIB"mstr_discrete"
CDS_LOCATION"C7A21"
SEC_TYPE"0402"
SEC"1"
ROOM"VDDQ_DEF_PWR_VR";
"A"
$PN"1"16;
"B"
$PN"2"17;
%"CAP"
"1","(-1750,75)","0","mstr_discrete","I80";
;
CDS_SEC"1"
PACK_TYPE"0805"
MATERIAL"X6S"
TOLERANCE"10%"
VOLTAGE"16V"
VALUE"10UF"
LOCATION"C3L17"
PART_NUMBER"C95333-007"
ROOM"VDDQ_DEF_PWR_VR"
SEC"1"
SEC_TYPE"0805"
CDS_LOCATION"C3L17"
CDS_LIB"mstr_discrete";
"A"
$PN"1"16;
"B"
$PN"2"17;
%"CAP"
"1","(-1975,75)","0","mstr_discrete","I81";
;
CDS_SEC"1"
PART_NUMBER"C95333-007"
PACK_TYPE"0805"
VALUE"10UF"
TOLERANCE"10%"
MATERIAL"X6S"
VOLTAGE"16V"
LOCATION"C3L16"
CDS_LIB"mstr_discrete"
CDS_LOCATION"C3L16"
SEC_TYPE"0805"
SEC"1"
ROOM"VDDQ_DEF_PWR_VR";
"A"
$PN"1"16;
"B"
$PN"2"17;
%"VCC_CORE"
"1","(-1975,400)","0","mstr_symbols","I83";
;
HDL_POWER"VR_FET_SW_P12V_STBY_PVDDQ_DEF"
CDS_LIB"mstr_symbols";
"A"16;
%"CAP"
"1","(-2200,75)","0","mstr_discrete","I84";
;
CDS_SEC"1"
PART_NUMBER"C95333-007"
MATERIAL"X6S"
TOLERANCE"10%"
VOLTAGE"16V"
VALUE"10UF"
PACK_TYPE"0805"
LOCATION"C3L15"
CDS_LOCATION"C3L15"
CDS_LIB"mstr_discrete"
ROOM"VDDQ_DEF_PWR_VR"
SEC_TYPE"0805"
SEC"1";
"A"
$PN"1"16;
"B"
$PN"2"17;
%"GND"
"1","(-2200,-225)","0","mstr_symbols","I85";
;
ROOM"VDDQ_DEF_PWR_VR"
BOM_COST"PROC_VRD_VCCIN_CPU0"
VOLTAGE"0"
SIZE"1B"
CDS_LIB"mstr_symbols"
BODY_TYPE"PLUMBING"
HDL_POWER"GND";
"A\NAC"17;
%"VCC_CORE"
"1","(-1800,2675)","0","mstr_symbols","I86";
;
HDL_POWER"VR_FET_SW_P12V_STBY_PVDDQ_DEF"
CDS_LIB"mstr_symbols";
"A"18;
%"CAP"
"1","(4450,1675)","0","mstr_discrete","I87";
;
CDS_SEC"1"
PACK_TYPE"0805LF"
LOCATION"C6A1"
VOLTAGE"4V"
VALUE"22UF"
GROUP"PWR_MLCC_CAP"
PART_NUMBER"C95333-002"
MATERIAL"X6S"
TOLERANCE"20%"
SEC_TYPE"0805LF"
SEC"1"
ROOM"VDDQ_DEF_PWR_VR"
CDS_LOCATION"C6A1"
BOM_COST"PROC_VRD_VCCIN_CPU0"
CDS_LIB"mstr_discrete";
"A"
$PN"1"1;
"B"
$PN"2"14;
%"P5V_STBY"
"1","(300,825)","0","mstr_symbols","I89";
;
SIZE"1B"
CDS_LIB"mstr_symbols"
VOLTAGE"5.0V"
BODY_TYPE"PLUMBING"
HDL_POWER"P5V_STBY";
"G\NAC"19;
END.
